G04 ================== begin FILE IDENTIFICATION RECORD ==================*
G04 Layout Name:  D:/<user>/Wistron_project/16315-1/gbr/16315-1.brd*
G04 Film Name:    P_OUTLINE*
G04 File Format:  Gerber RS274X*
G04 File Origin:  Cadence Allegro 16.5-S056*
G04 Origin Date:  Fri Jun 09 15:29:54 2017*
G04 *
G04 Layer:  BOARD GEOMETRY/PANEL_OUTLINE*
G04 *
G04 Offset:    (0.00 0.00)*
G04 Mirror:    No*
G04 Mode:      Positive*
G04 Rotation:  0*
G04 FullContactRelief:  No*
G04 UndefLineWidth:     6.00*
G04 ================== end FILE IDENTIFICATION RECORD ====================*
%FSLAX35Y35*MOIN*%
%IR0*IPPOS*OFA0.00000B0.00000*MIA0B0*SFA1.00000B1.00000*%
%ADD10C,.006*%
G75*
%LPD*%
G75*
G54D10*
G01X0Y-137756D02*
G03X15000Y-152756I15000J0D01*
G01X0Y-137756D02*
G03X15000Y-152756I15000J0D01*
G01X0Y-11811D02*
Y-137756D01*
G01Y-11811D02*
Y-137756D01*
G01X854331Y-152756D02*
X15000D01*
G01X854331D02*
X15000D01*
G01X23622Y-7874D02*
G03Y0I0J3937D01*
G01Y-7874D02*
G03Y0I0J3937D01*
G01X0Y3937D02*
G03X3937Y0I3937J0D01*
G01Y-7874D02*
X23622D01*
G01X0Y3937D02*
G03X3937Y0I3937J0D01*
G01Y-7874D02*
X23622D01*
G01X3937D02*
G03X0Y-11811I0J-3937D01*
G01X3937Y-7874D02*
G03X0Y-11811I0J-3937D01*
G01X3937Y0D02*
X397638D01*
G01X3937D02*
X397638D01*
G01X0Y1370866D02*
Y3937D01*
G01Y1370866D02*
Y3937D01*
G01X3937Y1374803D02*
G03X0Y1370866I0J-3937D01*
G01X3937Y1374803D02*
G03X0Y1370866I0J-3937D01*
G01X23622Y1374803D02*
G03Y1382677I0J3937D01*
G01Y1374803D02*
G03Y1382677I0J3937D01*
G01X3937D02*
X23622D01*
G01X0Y1386614D02*
G03X3937Y1382677I3937J0D01*
G01D02*
X23622D01*
G01X0Y1386614D02*
G03X3937Y1382677I3937J0D01*
G01Y1374803D02*
X746850D01*
G01D02*
X3937D01*
G01X0Y1386614D02*
Y1643268D01*
G01Y1386614D02*
Y1643268D01*
G01X15000Y1658268D02*
G03X0Y1643268I0J-15000D01*
G01X15000Y1658268D02*
G03X0Y1643268I0J-15000D01*
G01X775591Y1658268D02*
X15000D01*
G01X775591D02*
X15000D01*
G01X54331Y-7874D02*
X323228D01*
G01X54331D02*
X323228D01*
G01X54331Y0D02*
G03Y-7874I0J-3937D01*
G01Y0D02*
G03Y-7874I0J-3937D01*
G01Y1382677D02*
G03Y1374803I0J-3937D01*
G01Y1382677D02*
G03Y1374803I0J-3937D01*
G01Y1382677D02*
X353740D01*
G01X54331D02*
X353740D01*
G01X114295Y378885D02*
G03X148106I16905J-13531D01*
G01X114295D02*
G03X148106I16905J-13531D01*
G01X114295D02*
G03X121220Y392016I-30737J24602D01*
G01X114295Y378885D02*
G03X121220Y392016I-30737J24602D01*
G01X114295Y831641D02*
G03X121220Y844772I-30737J24601D01*
G01X114295Y831641D02*
G03X121220Y844772I-30737J24602D01*
G01X114295Y831641D02*
G03X148106I16905J-13531D01*
G01X114295D02*
G03X148106I16905J-13531D01*
G01X114295Y1284397D02*
G03X148106I16905J-13531D01*
G01X114295D02*
G03X148106I16905J-13531D01*
G01X114295D02*
G03X121220Y1297528I-30737J24601D01*
G01X114295Y1284397D02*
G03X121220Y1297528I-30737J24602D01*
G01X141181Y392016D02*
G03X121220I-9980J-3039D01*
G01X141181D02*
G03X148106Y378885I37662J11471D01*
G01X141181Y392016D02*
G03X121220I-9980J-3039D01*
G01X141181D02*
G03X148106Y378885I37662J11471D01*
G01X141181Y844772D02*
G03X148106Y831641I37662J11471D01*
G01X141181Y844772D02*
G03X148106Y831641I37662J11471D01*
G01X141181Y844772D02*
G03X121220I-9980J-3040D01*
G01X141181D02*
G03X121220I-9980J-3039D01*
G01X141181Y1297528D02*
G03X121220I-9980J-3040D01*
G01X141181D02*
G03X148106Y1284397I37662J11471D01*
G01X141181Y1297528D02*
G03X121220I-9980J-3040D01*
G01X141181D02*
G03X148106Y1284397I37662J11471D01*
G01X323228Y-7874D02*
G03Y0I0J3937D01*
G01Y-7874D02*
G03Y0I0J3937D01*
G01X362598D02*
G03Y-7874I0J-3937D01*
G01Y0D02*
G03Y-7874I0J-3937D01*
G01X362327Y378885D02*
G03X396138I16905J-13531D01*
G01X362327D02*
G03X396138I16905J-13531D01*
G01X362327D02*
G03X369252Y392016I-30737J24602D01*
G01X362327Y378885D02*
G03X369252Y392016I-30737J24602D01*
G01X362327Y831641D02*
G03X369252Y844772I-30737J24602D01*
G01X362327Y831641D02*
G03X369252Y844772I-30737J24602D01*
G01X362327Y831641D02*
G03X396138I16905J-13531D01*
G01X362327D02*
G03X396138I16905J-13531D01*
G01X362327Y1284397D02*
G03X396138I16905J-13531D01*
G01X362327D02*
G03X396138I16905J-13531D01*
G01X362327D02*
G03X369252Y1297528I-30737J24602D01*
G01X362327Y1284397D02*
G03X369252Y1297528I-30737J24602D01*
G01X353740Y1374803D02*
G03Y1382677I0J3937D01*
G01Y1374803D02*
G03Y1382677I0J3937D01*
G01X401575Y3937D02*
Y55118D01*
G01X397638Y0D02*
G03X401575Y3937I0J3937D01*
G01X409449D02*
Y51181D01*
G01X397638Y-7874D02*
G03X409449Y3937I0J11811D01*
G01X397638Y0D02*
G03X401575Y3937I0J3937D01*
G01D02*
Y55118D01*
G01X409449Y3937D02*
Y51181D01*
G01X397638Y-7874D02*
G03X409449Y3937I0J11811D01*
G01X362598Y-7874D02*
X397638D01*
G01X362598D02*
X397638D01*
G01X405512Y59055D02*
G03X401575Y55118I0J-3937D01*
G01X405512Y59055D02*
G03X401575Y55118I0J-3937D01*
G01X405512Y59055D02*
X586614D01*
G01X409449Y51181D02*
X582677D01*
G01X405512Y59055D02*
X586614D01*
G01X409449Y51181D02*
X582677D01*
G01X389213Y392016D02*
G03X396138Y378885I37662J11471D01*
G01X389213Y392016D02*
G03X396138Y378885I37662J11471D01*
G01X389213Y392016D02*
G03X369252I-9981J-3039D01*
G01X389213D02*
G03X369252I-9981J-3039D01*
G01X389213Y844772D02*
G03X396138Y831641I37662J11471D01*
G01X389213Y844772D02*
G03X396138Y831641I37662J11471D01*
G01X389213Y844772D02*
G03X369252I-9981J-3040D01*
G01X389213D02*
G03X369252I-9981J-3039D01*
G01X389213Y1297528D02*
G03X396138Y1284397I37662J11471D01*
G01X389213Y1297528D02*
G03X396138Y1284397I37662J11471D01*
G01X389213Y1297528D02*
G03X369252I-9981J-3040D01*
G01X389213D02*
G03X369252I-9981J-3040D01*
G01X393110Y1382677D02*
G03Y1374803I0J-3937D01*
G01Y1382677D02*
X692520D01*
G01X393110D02*
X692520D01*
G01X393110D02*
G03Y1374803I0J-3937D01*
G01X523327Y829921D02*
G03X483169I-20079J0D01*
G01X523327D02*
G03I-20079J0D01*
G01X483169D02*
G03X523327I20079J0D01*
G01X594488Y-7874D02*
X628765D01*
G01X594488D02*
X628765D01*
G01X590551Y55118D02*
Y3937D01*
G01D02*
G03X594488Y0I3937J0D01*
G01X582677Y51181D02*
Y3937D01*
G01D02*
G03X594488Y-7874I11811J0D01*
G01X590551Y55118D02*
Y3937D01*
G01D02*
G03X594488Y0I3937J0D01*
G01X582677Y51181D02*
Y3937D01*
G01D02*
G03X594488Y-7874I11811J0D01*
G01Y0D02*
X783465D01*
G01X594488D02*
X783465D01*
G01X590551Y55118D02*
G03X586614Y59055I-3937J0D01*
G01X590551Y55118D02*
G03X586614Y59055I-3937J0D01*
G01X628765Y-7874D02*
G03Y0I0J3937D01*
G01Y-7874D02*
G03Y0I0J3937D01*
G01X610358Y378885D02*
G03X644169I16906J-13531D01*
G01X610358D02*
G03X644169I16906J-13531D01*
G01X637244Y392016D02*
G03X644169Y378885I37662J11471D01*
G01X637244Y392016D02*
G03X644169Y378885I37662J11471D01*
G01X637244Y392016D02*
G03X617283I-9980J-3039D01*
G01X637244D02*
G03X617283I-9980J-3039D01*
G01X610358Y378885D02*
G03X617283Y392016I-30737J24602D01*
G01X610358Y378885D02*
G03X617283Y392016I-30737J24602D01*
G01X637244Y844772D02*
G03X644169Y831641I37662J11471D01*
G01X637244Y844772D02*
G03X644169Y831641I37662J11471D01*
G01X610358D02*
G03X617283Y844772I-30737J24601D01*
G01X610358Y831641D02*
G03X617283Y844772I-30737J24602D01*
G01X610358Y831641D02*
G03X644169I16906J-13531D01*
G01X610358D02*
G03X644169I16906J-13531D01*
G01X637244Y844772D02*
G03X617283I-9980J-3040D01*
G01X637244D02*
G03X617283I-9980J-3039D01*
G01X610358Y1284397D02*
G03X644169I16906J-13531D01*
G01X610358D02*
G03X644169I16906J-13531D01*
G01X637244Y1297528D02*
G03X644169Y1284397I37662J11471D01*
G01X637244Y1297528D02*
G03X644169Y1284397I37662J11471D01*
G01X610358D02*
G03X617283Y1297528I-30737J24601D01*
G01X637244D02*
G03X617283I-9980J-3040D01*
G01X610358Y1284397D02*
G03X617283Y1297528I-30737J24602D01*
G01X637244D02*
G03X617283I-9980J-3040D01*
G01X659474Y0D02*
G03Y-7874I0J-3937D01*
G01Y0D02*
G03Y-7874I0J-3937D01*
G01D02*
X780203D01*
G01X659474D02*
X780203D01*
G01X692520Y1374803D02*
G03Y1382677I0J3937D01*
G01Y1374803D02*
G03Y1382677I0J3937D01*
G01X746850Y1374803D02*
G03X750787Y1378740I0J3937D01*
G01X746850Y1374803D02*
G03X750787Y1378740I0J3937D01*
G01X723228Y1382677D02*
G03Y1374803I0J-3937D01*
G01Y1382677D02*
X742913D01*
G01X723228D02*
X742913D01*
G01X723228D02*
G03Y1374803I0J-3937D01*
G01X742913Y1464567D02*
Y1382677D01*
G01Y1464567D02*
Y1382677D01*
G01X754724Y1476378D02*
G03X742913Y1464567I0J-11811D01*
G01X754724Y1476378D02*
G03X742913Y1464567I0J-11811D01*
G01X862205Y-7874D02*
X791339D01*
G01X787402Y-3937D02*
G03X791339Y-7874I3937J0D01*
G01X787402Y-3937D02*
G03X791339Y-7874I3937J0D01*
G01D02*
X862205D01*
G01X858268Y-15748D02*
X791339D01*
G01X858268D02*
X791339D01*
G01X787402Y-3937D02*
G03X783465Y0I-3937J0D01*
G01X787402Y-3937D02*
G03X783465Y0I-3937J0D01*
G01X780203Y-7874D02*
G03X791339Y-15748I11136J3937D01*
G01X780203Y-7874D02*
G03X791339Y-15748I11136J3937D01*
G01X779551Y264712D02*
G03X813362I16905J-13531D01*
G01X779551D02*
G03X813362I16905J-13531D01*
G01X779551D02*
G03X786476Y277843I-30737J24601D01*
G01X806437D02*
G03X786476I-9981J-3040D01*
G01X779551Y264712D02*
G03X786476Y277843I-30737J24602D01*
G01X806437D02*
G03X786476I-9981J-3040D01*
G01X779551Y737153D02*
G03X786476Y750284I-30737J24601D01*
G01X779551Y737154D02*
G03X786476Y750284I-30736J24602D01*
G01X779551Y737153D02*
G03X813362I16905J-13531D01*
G01X779551D02*
G03X813362I16905J-13531D01*
G01X806437Y750284D02*
G03X786476I-9981J-3040D01*
G01X806437D02*
G03X786476I-9981J-3040D01*
G01X750787Y1464567D02*
Y1378740D01*
G01Y1464567D02*
Y1378740D01*
G01X783465Y1468504D02*
G03X787402Y1472441I0J3937D01*
G01X783465Y1468504D02*
G03X787402Y1472441I0J3937D01*
G01X783465Y1468504D02*
X754724D01*
G01D02*
G03X750787Y1464567I0J-3937D01*
G01X783465Y1468504D02*
X754724D01*
G01D02*
G03X750787Y1464567I0J-3937D01*
G01X779528Y1476378D02*
X754724D01*
G01X779528D02*
X754724D01*
G01X787402Y1654331D02*
Y1472441D01*
G01X779528Y1596063D02*
Y1476378D01*
G01X787402Y1654331D02*
Y1472441D01*
G01X779528Y1596063D02*
Y1476378D01*
G01X787402Y1596063D02*
G03X779528I-3937J0D01*
G01X787402D02*
G03X779528I-3937J0D01*
G01X1216535Y1658268D02*
X791339D01*
G01D02*
G03X787402Y1654331I0J-3937D01*
G01X779528D02*
G03X775591Y1658268I-3937J0D01*
G01X1216535D02*
X791339D01*
G01D02*
G03X787402Y1654331I0J-3937D01*
G01X779528D02*
G03X775591Y1658268I-3937J0D01*
G01X779528Y1654331D02*
Y1626772D01*
G01D02*
G03X787402I3937J0D01*
G01X779528Y1654331D02*
Y1626772D01*
G01D02*
G03X787402I3937J0D01*
G01X806437Y277843D02*
G03X813362Y264712I37662J11471D01*
G01X806437Y277843D02*
G03X813362Y264712I37662J11471D01*
G01X806437Y750284D02*
G03X813362Y737153I37662J11471D01*
G01X806437Y750284D02*
G03X813362Y737154I37661J11472D01*
G01X866142Y-148819D02*
Y-11811D01*
G01Y-148819D02*
G03X870079Y-152756I3937J0D01*
G01X866142Y-11811D02*
Y-148819D01*
G01D02*
G03X870079Y-152756I3937J0D01*
G01X866142Y-129134D02*
G03X858268I-3937J0D01*
G01X866142D02*
G03X858268I-3937J0D01*
G01Y-148819D02*
Y-129134D01*
G01X854331Y-152756D02*
G03X858268Y-148819I0J3937D01*
G01D02*
Y-129134D01*
G01X854331Y-152756D02*
G03X858268Y-148819I0J3937D01*
G01X1177165Y-152756D02*
X870079D01*
G01D02*
X1177165D01*
G01X858268Y-98425D02*
Y-15748D01*
G01Y-98425D02*
Y-15748D01*
G01Y-98425D02*
G03X866142I3937J0D01*
G01X858268D02*
G03X866142I3937J0D01*
G01Y-11811D02*
G03X862205Y-7874I-3937J0D01*
G01X866142Y-11811D02*
G03X862205Y-7874I-3937J0D01*
G01X927032Y-57820D02*
G03X962731I17850J-12259D01*
G01X927032Y-57821D02*
G03X962732I17850J-12258D01*
G01X927032Y-57820D02*
G03X935199Y-42571I-64908J44575D01*
G01X954565D02*
G03X935199I-9683J-3885D01*
G01X927032Y-57821D02*
G03X935199Y-42571I-64909J44573D01*
G01X954564D02*
G03X935199I-9682J-3885D01*
G01X944512Y1089122D02*
G03X978323I16905J-13531D01*
G01X944512Y1089121D02*
G03X978323I16905J-13531D01*
G01X944512Y1431641D02*
G03X978323I16905J-13531D01*
G01X944512D02*
G03X978323I16905J-13531D01*
G01X954565Y-42571D02*
G03X962731Y-57820I73077J29322D01*
G01X954564Y-42570D02*
G03X962732Y-57821I73076J29324D01*
G01X971398Y1102252D02*
G03X978323Y1089122I37661J11472D01*
G01X971398Y1102252D02*
G03X978323Y1089121I37662J11471D01*
G01X971398Y1102252D02*
G03X951437I-9980J-3039D01*
G01X971398D02*
G03X951437I-9980J-3039D01*
G01X944512Y1089122D02*
G03X951437Y1102252I-30737J24602D01*
G01X944512Y1089121D02*
G03X951437Y1102252I-30737J24602D01*
G01X971398Y1444772D02*
G03X978323Y1431641I37662J11471D01*
G01X971398Y1444772D02*
G03X978323Y1431641I37662J11471D01*
G01X971398Y1444772D02*
G03X951437I-9980J-3040D01*
G01X944512Y1431641D02*
G03X951437Y1444772I-30737J24602D01*
G01X944512Y1431641D02*
G03X951437Y1444772I-30737J24602D01*
G01X971398D02*
G03X951437I-9980J-3039D01*
G01X1181102Y-148819D02*
Y-3937D01*
G01X1177165Y-152756D02*
G03X1181102Y-148819I0J3937D01*
G01X1177165Y-152756D02*
G03X1181102Y-148819I0J3937D01*
G01D02*
Y-3937D01*
G01Y-94488D02*
G03X1188976I3937J0D01*
G01X1181102D02*
G03X1188976I3937J0D01*
G01Y-125197D02*
G03X1181102I-3937J0D01*
G01X1188976D02*
G03X1181102I-3937J0D01*
G01X1185039Y0D02*
G03X1181102Y-3937I0J-3937D01*
G01X1185039Y0D02*
G03X1181102Y-3937I0J-3937D01*
G01X1164984Y557626D02*
G03X1198795I16906J-13531D01*
G01X1164984Y557625D02*
G03X1198795I16906J-13531D01*
G01X1191870Y570756D02*
G03X1171909I-9980J-3039D01*
G01X1191870D02*
G03X1171909I-9980J-3039D01*
G01X1164984Y557626D02*
G03X1171909Y570756I-30736J24602D01*
G01X1164984Y557625D02*
G03X1171909Y570756I-30737J24602D01*
G01X1164984Y971011D02*
G03X1198795I16906J-13531D01*
G01X1164984D02*
G03X1198795I16906J-13531D01*
G01X1191870Y984142D02*
G03X1171909I-9980J-3040D01*
G01X1191870D02*
G03X1171909I-9980J-3039D01*
G01X1164984Y971011D02*
G03X1171909Y984142I-30737J24602D01*
G01X1164984Y971011D02*
G03X1171909Y984142I-30737J24602D01*
G01X1164173Y1378740D02*
Y1468504D01*
G01X1930906Y1374803D02*
X1168110D01*
G01X1164173Y1378740D02*
G03X1168110Y1374803I3937J0D01*
G01X1172047Y1382677D02*
Y1464567D01*
G01X1195669Y1382677D02*
X1172047D01*
G01X1930906Y1374803D02*
X1168110D01*
G01X1164173Y1378740D02*
G03X1168110Y1374804I3937J1D01*
G01X1164173Y1378740D02*
Y1468504D01*
G01X1172047Y1382677D02*
Y1464567D01*
G01X1195669Y1382677D02*
X1172047D01*
G01X1168110Y1472441D02*
G03X1164173Y1468504I0J-3937D01*
G01X1168110Y1472441D02*
G03X1164173Y1468504I0J-3937D01*
G01X1172047Y1464567D02*
X1216535D01*
G01X1172047D02*
X1216535D01*
G01X1168110Y1472441D02*
X1216535D01*
G01X1168110D02*
X1216535D01*
G01X1164984Y1561563D02*
G03X1171909Y1574693I-30736J24602D01*
G01X1164984Y1561562D02*
G03X1171909Y1574693I-30737J24602D01*
G01X1164984Y1561563D02*
G03X1198795I16906J-13531D01*
G01X1164984Y1561562D02*
G03X1198795I16906J-13531D01*
G01X1191870Y1574693D02*
G03X1171909I-9980J-3039D01*
G01X1191870D02*
G03X1171909I-9980J-3039D01*
G01X1188976Y-148819D02*
Y-125197D01*
G01Y-148819D02*
G03X1192913Y-152756I3937J0D01*
G01X1188976Y-148819D02*
Y-125197D01*
G01Y-148819D02*
G03X1192913Y-152756I3937J0D01*
G01D02*
X1919843D01*
G01X1192913D02*
X1919843D01*
G01X1188976Y-94488D02*
Y-7874D01*
G01Y-94488D02*
Y-7874D01*
G01X1185039Y0D02*
X1366142D01*
G01X1188976Y-7874D02*
X1315748D01*
G01X1185039Y0D02*
X1366142D01*
G01X1188976Y-7874D02*
X1315748D01*
G01X1191870Y570756D02*
G03X1198795Y557626I37662J11472D01*
G01X1191870Y570756D02*
G03X1198795Y557626I37662J11472D01*
G01X1191870Y984142D02*
G03X1198795Y971011I37662J11471D01*
G01X1191870Y984142D02*
G03X1198795Y971011I37662J11471D01*
G01X1524606Y1382677D02*
X1226378D01*
G01X1524606D02*
X1226378D01*
G01X1195669Y1374803D02*
G03Y1382677I0J3937D01*
G01X1226378D02*
G03Y1374803I0J-3937D01*
G01X1195669D02*
G03Y1382677I0J3937D01*
G01X1226378D02*
G03Y1374803I0J-3937D01*
G01X1216535Y1464567D02*
G03X1228346Y1476378I0J11811D01*
G01X1216535Y1464567D02*
G03X1228346Y1476378I0J11811D01*
G01Y1592126D02*
Y1476378D01*
G01Y1592126D02*
Y1476378D01*
G01X1220472Y1654331D02*
Y1476378D01*
G01X1216535Y1472441D02*
G03X1220472Y1476378I0J3937D01*
G01X1216535Y1472441D02*
G03X1220472Y1476378I0J3937D01*
G01D02*
Y1654331D01*
G01X1191870Y1574693D02*
G03X1198795Y1561563I37662J11472D01*
G01X1191870Y1574693D02*
G03X1198795Y1561562I37662J11471D01*
G01X1228346Y1592126D02*
G03X1220472I-3937J0D01*
G01X1228346D02*
G03X1220472I-3937J0D01*
G01X1232283Y1658268D02*
X1442382D01*
G01X1232283D02*
G03X1228346Y1654331I0J-3937D01*
G01X1232283Y1658268D02*
X1442382D01*
G01X1232283D02*
G03X1228346Y1654331I0J-3937D01*
G01D02*
Y1622835D01*
G01Y1654331D02*
Y1622835D01*
G01X1220472Y1654331D02*
G03X1216535Y1658268I-3937J0D01*
G01X1220472Y1654331D02*
G03X1216535Y1658268I-3937J0D01*
G01X1220472Y1622835D02*
G03X1228346I3937J0D01*
G01X1220472D02*
G03X1228346I3937J0D01*
G01X1284965Y378885D02*
G03X1318776I16906J-13531D01*
G01X1284965D02*
G03X1318775I16905J-13531D01*
G01X1284965Y831641D02*
G03X1318776I16906J-13531D01*
G01X1284965D02*
G03X1318775I16905J-13531D01*
G01X1284965Y1284397D02*
G03X1318776I16906J-13531D01*
G01X1284965D02*
G03X1318775I16905J-13531D01*
G01X1315748Y-7874D02*
G03Y0I0J3937D01*
G01Y-7874D02*
G03Y0I0J3937D01*
G01X1311850Y392016D02*
G03X1291890I-9980J-3040D01*
G01X1311850D02*
G03X1318776Y378885I37662J11473D01*
G01X1311851Y392016D02*
G03X1291890I-9980J-3039D01*
G01X1311851D02*
G03X1318775Y378885I37663J11469D01*
G01X1284965D02*
G03X1291890Y392016I-30737J24602D01*
G01X1284965Y378885D02*
G03X1291890Y392016I-30737J24602D01*
G01X1284965Y831641D02*
G03X1291890Y844772I-30737J24602D01*
G01X1311850D02*
G03X1318776Y831641I37662J11473D01*
G01X1284965D02*
G03X1291890Y844772I-30737J24602D01*
G01X1311851D02*
G03X1318775Y831641I37663J11469D01*
G01X1311850Y844772D02*
G03X1291890I-9980J-3040D01*
G01X1311851D02*
G03X1291890I-9980J-3039D01*
G01X1284965Y1284397D02*
G03X1291890Y1297528I-30737J24602D01*
G01X1311850D02*
G03X1291890I-9980J-3040D01*
G01X1311850D02*
G03X1318776Y1284397I37661J11473D01*
G01X1284965D02*
G03X1291890Y1297528I-30737J24602D01*
G01X1311851D02*
G03X1291890I-9980J-3040D01*
G01X1311851D02*
G03X1318775Y1284397I37663J11469D01*
G01X1377953Y3937D02*
Y51181D01*
G01Y3937D02*
Y51181D01*
G01X1370079Y3937D02*
Y55118D01*
G01X1366142Y0D02*
G03X1370079Y3937I0J3937D01*
G01X1366142Y-7874D02*
G03X1377953Y3937I0J11811D01*
G01X1346457Y-7874D02*
X1366142D01*
G01Y0D02*
G03X1370079Y3937I0J3937D01*
G01D02*
Y55118D01*
G01X1346457Y-7874D02*
X1366142D01*
G01D02*
G03X1377953Y3937I0J11811D01*
G01X1346457Y0D02*
G03Y-7874I0J-3937D01*
G01Y0D02*
G03Y-7874I0J-3937D01*
G01X1374016Y59055D02*
G03X1370079Y55118I0J-3937D01*
G01X1374016Y59056D02*
G03X1370079Y55118I0J-3937D01*
G01X1374016Y59055D02*
X1555118D01*
G01X1377953Y51181D02*
X1551181D01*
G01X1374016Y59055D02*
X1555118D01*
G01X1377953Y51181D02*
X1551181D01*
G01X1442382Y1658268D02*
G03X1450256I3937J0D01*
G01X1442382D02*
G03X1450256I3937J0D01*
G01D02*
X1919843D01*
G01X1450256D02*
X1919843D01*
G01X1562992Y0D02*
X1930906D01*
G01X1559055Y55118D02*
Y3937D01*
G01D02*
G03X1562992Y0I3937J0D01*
G01Y-7874D02*
X1593701D01*
G01X1559055Y55118D02*
Y3937D01*
G01D02*
G03X1562992Y0I3937J0D01*
G01D02*
X1930906D01*
G01X1562992Y-7874D02*
X1593701D01*
G01X1551181Y51181D02*
Y3937D01*
G01D02*
G03X1562992Y-7874I11811J0D01*
G01X1551181Y51181D02*
Y3937D01*
G01D02*
G03X1562992Y-7874I11811J0D01*
G01X1559055Y55118D02*
G03X1555118Y59055I-3937J0D01*
G01X1559055Y55118D02*
G03X1555118Y59055I-3937J0D01*
G01X1532996Y378885D02*
G03X1566807I16906J-13531D01*
G01X1532996D02*
G03X1566807I16906J-13531D01*
G01X1559882Y392016D02*
G03X1566807Y378885I37662J11471D01*
G01X1559882Y392016D02*
G03X1566807Y378885I37662J11471D01*
G01X1559882Y392016D02*
G03X1539921I-9980J-3039D01*
G01X1559882D02*
G03X1539921I-9980J-3039D01*
G01X1532996Y378885D02*
G03X1539921Y392016I-30737J24602D01*
G01X1532996Y378885D02*
G03X1539921Y392016I-30737J24602D01*
G01X1559882Y844772D02*
G03X1566807Y831641I37662J11471D01*
G01X1559882Y844772D02*
G03X1566807Y831641I37662J11471D01*
G01X1532996D02*
G03X1539921Y844772I-30737J24602D01*
G01X1532996Y831641D02*
G03X1539921Y844772I-30737J24602D01*
G01X1532996Y831641D02*
G03X1566807I16906J-13531D01*
G01X1532996D02*
G03X1566807I16906J-13531D01*
G01X1559882Y844772D02*
G03X1539921I-9980J-3040D01*
G01X1559882D02*
G03X1539921I-9980J-3039D01*
G01X1532996Y1284397D02*
G03X1566807I16906J-13531D01*
G01X1532996D02*
G03X1566807I16906J-13531D01*
G01X1559882Y1297528D02*
G03X1566807Y1284397I37662J11471D01*
G01X1559882Y1297528D02*
G03X1566807Y1284397I37662J11471D01*
G01X1559882Y1297528D02*
G03X1539921I-9980J-3040D01*
G01X1532996Y1284397D02*
G03X1539921Y1297528I-30737J24602D01*
G01X1532996Y1284397D02*
G03X1539921Y1297528I-30737J24602D01*
G01X1559882D02*
G03X1539921I-9980J-3040D01*
G01X1563976Y1382677D02*
G03Y1374803I0J-3937D01*
G01Y1382677D02*
G03Y1374803I0J-3937D01*
G01X1524606D02*
G03Y1382677I0J3937D01*
G01Y1374803D02*
G03Y1382677I0J3937D01*
G01X1864567D02*
X1563976D01*
G01X1864567D02*
X1563976D01*
G01X1593701Y-7874D02*
G03Y0I0J3937D01*
G01Y-7874D02*
G03Y0I0J3937D01*
G01X1633071D02*
G03Y-7874I0J-3937D01*
G01D02*
X1880512D01*
G01X1633071D02*
X1880512D01*
G01X1633071Y0D02*
G03Y-7874I0J-3937D01*
G01X1693996Y829921D02*
G03X1653839I-20078J0D01*
G01X1693996D02*
G03I-20079J0D01*
G01X1653839D02*
G03X1693996I20078J0D01*
G01X1781028Y378885D02*
G03X1814839I16906J-13531D01*
G01X1781028D02*
G03X1814838I16905J-13531D01*
G01X1807913Y392016D02*
G03X1814839Y378885I37662J11473D01*
G01X1807914Y392016D02*
G03X1814838Y378885I37663J11469D01*
G01X1807913Y392016D02*
G03X1787953I-9980J-3040D01*
G01X1807914D02*
G03X1787953I-9980J-3039D01*
G01X1781028Y378885D02*
G03X1787953Y392016I-30737J24602D01*
G01X1781028Y378885D02*
G03X1787953Y392016I-30737J24602D01*
G01X1807913Y844772D02*
G03X1814839Y831641I37662J11473D01*
G01X1807914Y844772D02*
G03X1814838Y831641I37663J11469D01*
G01X1781028D02*
G03X1787953Y844772I-30737J24602D01*
G01X1781028Y831641D02*
G03X1787953Y844772I-30737J24602D01*
G01X1781028Y831641D02*
G03X1814839I16906J-13531D01*
G01X1781028D02*
G03X1814838I16905J-13531D01*
G01X1807913Y844772D02*
G03X1787953I-9980J-3040D01*
G01X1807914D02*
G03X1787953I-9980J-3039D01*
G01X1781028Y1284397D02*
G03X1814839I16906J-13531D01*
G01X1781028D02*
G03X1814838I16905J-13531D01*
G01X1807913Y1297528D02*
G03X1814839Y1284397I37661J11473D01*
G01X1807914Y1297528D02*
G03X1814838Y1284397I37663J11469D01*
G01X1807913Y1297528D02*
G03X1787953I-9980J-3040D01*
G01X1781028Y1284397D02*
G03X1787953Y1297528I-30737J24602D01*
G01X1781028Y1284397D02*
G03X1787953Y1297528I-30737J24602D01*
G01X1807914D02*
G03X1787953I-9980J-3040D01*
G01X1911220Y0D02*
G03Y-7874I0J-3937D01*
G01Y0D02*
G03Y-7874I0J-3937D01*
G01X1880512D02*
G03Y0I0J3937D01*
G01Y-7874D02*
G03Y0I0J3937D01*
G01X1930906Y1382677D02*
X1895276D01*
G01D02*
G03Y1374803I0J-3937D01*
G01X1930906Y1382677D02*
X1895276D01*
G01D02*
G03Y1374803I0J-3937D01*
G01X1864567D02*
G03Y1382677I0J3937D01*
G01Y1374803D02*
G03Y1382677I0J3937D01*
G01X1919843Y-152756D02*
G03X1934843Y-137756I0J15000D01*
G01X1919843Y-152756D02*
G03X1934843Y-137756I0J15000D01*
G01Y-11811D02*
Y-137756D01*
G01Y-11811D02*
Y-137756D01*
G01X1930906Y0D02*
G03X1934843Y3937I0J3937D01*
G01X1930906Y0D02*
G03X1934843Y3937I0J3937D01*
G01Y-11811D02*
G03X1930906Y-7874I-3937J0D01*
G01X1934843Y-11811D02*
G03X1930906Y-7874I-3937J0D01*
G01X1911220D02*
X1930906D01*
G01X1911220D02*
X1930906D01*
G01X1934843Y1370866D02*
Y3937D01*
G01D02*
Y1370866D01*
G01D02*
G03X1930906Y1374803I-3937J0D01*
G01X1934843Y1370866D02*
G03X1930906Y1374803I-3937J0D01*
G01Y1382677D02*
G03X1934843Y1386614I0J3937D01*
G01X1930906Y1382677D02*
G03X1934843Y1386614I0J3937D01*
G01D02*
Y1643268D01*
G01Y1386614D02*
Y1643268D01*
G01D02*
G03X1919843Y1658268I-15000J0D01*
G01X1934843Y1643268D02*
G03X1919843Y1658268I-15000J0D01*
M02*
